(kicad_pcb
	(version 20260206)
	(generator "pcbnew")
	(generator_version "10.0")
	(general
		(thickness 1.6)
		(legacy_teardrops no)
	)
	(paper "A4")
	(title_block
		(title "v2-tray-backplane — ms_tbp_v2.brd")
		(comment 1 "Open CloudServer (Microsoft) / footprints 53-58 of 164")
	)
	(layers
		(0 "F.Cu" signal "TOP")
		(4 "In1.Cu" signal "LYR2")
		(6 "In2.Cu" signal "LYR3")
		(8 "In3.Cu" signal "LYR4")
		(10 "In4.Cu" signal "LYR5")
		(12 "In5.Cu" signal "LYR6")
		(14 "In6.Cu" signal "LYR7")
		(2 "B.Cu" signal "BOTTOM")
		(9 "F.Adhes" user "F.Adhesive")
		(11 "B.Adhes" user "B.Adhesive")
		(13 "F.Paste" user "Package Geometry/Pastemask Top")
		(15 "B.Paste" user "Package Geometry/Pastemask Bottom")
		(5 "F.SilkS" user "Ref Des/Silkscreen Top")
		(7 "B.SilkS" user "Ref Des/Silkscreen Bottom")
		(1 "F.Mask" user "Board Geometry/Soldermask Top")
		(3 "B.Mask" user "Board Geometry/Soldermask Bottom")
		(17 "Dwgs.User" user "User.Drawings")
		(19 "Cmts.User" user "User.Comments")
		(21 "Eco1.User" user "User.Eco1")
		(23 "Eco2.User" user "User.Eco2")
		(25 "Edge.Cuts" user "Board Geometry/Outline")
		(27 "Margin" user)
		(31 "F.CrtYd" user "Package Geometry/Place Bound Top")
		(29 "B.CrtYd" user "Package Geometry/Place Bound Bottom")
		(35 "F.Fab" user "Ref Des/Assembly Top")
		(33 "B.Fab" user "Ref Des/Assembly Bottom")
	)
	(footprint ""
		(layer "F.Cu")
		(at -331.5462 3.0226 -90)
		(property "Reference" "J25"
			(at 0.49022 -4.06146 90)
			(unlocked yes)
			(layer "F.SilkS")
			(effects
				(font
					(size 0.762 0.5334)
					(thickness 0.1016)
				)
			)
		)
		(property "Value" ""
			(at 0 0 270)
			(layer "F.Fab")
			(effects
				(font
					(size 1.27 1.27)
				)
			)
		)
		(duplicate_pad_numbers_are_jumpers no)
		(fp_line
			(start -2.54 1.27)
			(end 0.127 1.27)
			(stroke
				(width 0.127)
				(type default)
			)
			(layer "F.SilkS")
		)
		(fp_line
			(start 2.443175 1.257198)
			(end 2.570175 1.257198)
			(stroke
				(width 0.127)
				(type default)
			)
			(layer "F.SilkS")
		)
		(fp_line
			(start 2.570175 1.257198)
			(end 2.570175 -1.282802)
			(stroke
				(width 0.127)
				(type default)
			)
			(layer "F.SilkS")
		)
		(fp_line
			(start -2.54 -1.27)
			(end -2.54 1.27)
			(stroke
				(width 0.127)
				(type default)
			)
			(layer "F.SilkS")
		)
		(fp_line
			(start -2.413 -1.27)
			(end -2.54 -1.27)
			(stroke
				(width 0.127)
				(type default)
			)
			(layer "F.SilkS")
		)
		(fp_line
			(start 2.570175 -1.282802)
			(end -0.096825 -1.282802)
			(stroke
				(width 0.127)
				(type default)
			)
			(layer "F.SilkS")
		)
		(fp_poly
			(pts
				(xy 0.127 3.683) (xy 0.127 1.778) (xy -3.048 1.778) (xy -3.048 -1.778) (xy -2.413 -1.778) (xy -2.413 -3.683)
				(xy -0.127 -3.683) (xy -0.127 -1.778) (xy 3.048 -1.778) (xy 3.048 1.778) (xy 2.413 1.778) (xy 2.413 3.683)
			)
			(stroke
				(width 0)
				(type default)
			)
			(fill no)
			(layer "F.CrtYd")
		)
		(fp_line
			(start -2.54 1.27)
			(end -2.54 -1.27)
			(stroke
				(width 0.1)
				(type default)
			)
			(layer "F.Fab")
		)
		(fp_line
			(start 2.54 1.27)
			(end -2.54 1.27)
			(stroke
				(width 0.1)
				(type default)
			)
			(layer "F.Fab")
		)
		(fp_line
			(start -2.54 -1.27)
			(end 2.54 -1.27)
			(stroke
				(width 0.1)
				(type default)
			)
			(layer "F.Fab")
		)
		(fp_line
			(start 2.54 -1.27)
			(end 2.54 1.27)
			(stroke
				(width 0.1)
				(type default)
			)
			(layer "F.Fab")
		)
		(fp_text user "*"
			(at -1.27 -3.89255 90)
			(unlocked yes)
			(layer "F.SilkS")
			(effects
				(font
					(size 0.381 0.381)
					(thickness 0.381)
				)
			)
		)
		(pad "1" smd rect
			(at -1.27 -1.4605 270)
			(size 1.27 3.429)
			(layers "F.Cu" "F.Mask" "F.Paste")
			(net "BLADE_B1_EN1")
		)
		(pad "2" smd rect
			(at 1.27 1.4605 270)
			(size 1.27 3.429)
			(layers "F.Cu" "F.Mask" "F.Paste")
			(net "UNNAMED_4_1X2HDR_I81_IO")
		)
	)
	(footprint ""
		(layer "F.Cu")
		(at -279.610401 45.631202)
		(property "Reference" "FB2"
			(at -0.932599 1.142898 0)
			(unlocked yes)
			(layer "F.SilkS")
			(effects
				(font
					(size 0.762 0.5334)
					(thickness 0.1016)
				)
				(justify left)
			)
		)
		(property "Value" ""
			(at 0 0 0)
			(layer "F.Fab")
			(effects
				(font
					(size 1.27 1.27)
				)
			)
		)
		(duplicate_pad_numbers_are_jumpers no)
		(fp_poly
			(pts
				(xy -1.016 0.508) (xy -1.016 -0.508) (xy 1.016 -0.508) (xy 1.016 0.508)
			)
			(stroke
				(width 0)
				(type default)
			)
			(fill no)
			(layer "F.CrtYd")
		)
		(fp_line
			(start -0.508 -0.254)
			(end 0.508 -0.254)
			(stroke
				(width 0.1)
				(type default)
			)
			(layer "F.Fab")
		)
		(fp_line
			(start -0.508 0.254)
			(end -0.508 -0.254)
			(stroke
				(width 0.1)
				(type default)
			)
			(layer "F.Fab")
		)
		(fp_line
			(start 0.508 -0.254)
			(end 0.508 0.254)
			(stroke
				(width 0.1)
				(type default)
			)
			(layer "F.Fab")
		)
		(fp_line
			(start 0.508 0.254)
			(end -0.508 0.254)
			(stroke
				(width 0.1)
				(type default)
			)
			(layer "F.Fab")
		)
		(pad "1" smd rect
			(at -0.4572 0 90)
			(size 0.508 0.5842)
			(layers "F.Cu" "F.Mask" "F.Paste")
			(net "P3V3_10G_B1_VCCT")
		)
		(pad "2" smd rect
			(at 0.4572 0 90)
			(size 0.508 0.5842)
			(layers "F.Cu" "F.Mask" "F.Paste")
			(net "UNNAMED_4_FERRITE_I151_B")
		)
	)
	(footprint ""
		(layer "F.Cu")
		(at -279.610401 43.345202)
		(property "Reference" "C5"
			(at 2.242401 -0.000102 0)
			(unlocked yes)
			(layer "F.SilkS")
			(effects
				(font
					(size 0.762 0.5334)
					(thickness 0.1016)
				)
			)
		)
		(property "Value" ""
			(at 0 0 0)
			(layer "F.Fab")
			(effects
				(font
					(size 1.27 1.27)
				)
			)
		)
		(duplicate_pad_numbers_are_jumpers no)
		(fp_poly
			(pts
				(xy -0.999299 0.503999) (xy -0.999299 -0.504) (xy 0.9993 -0.504) (xy 0.9993 0.503999)
			)
			(stroke
				(width 0)
				(type default)
			)
			(fill no)
			(layer "F.CrtYd")
		)
		(fp_line
			(start -0.499999 -0.25)
			(end 0.499999 -0.25)
			(stroke
				(width 0.1)
				(type default)
			)
			(layer "F.Fab")
		)
		(fp_line
			(start -0.499999 0.249999)
			(end -0.499999 -0.25)
			(stroke
				(width 0.1)
				(type default)
			)
			(layer "F.Fab")
		)
		(fp_line
			(start 0.499999 -0.25)
			(end 0.499999 0.249999)
			(stroke
				(width 0.1)
				(type default)
			)
			(layer "F.Fab")
		)
		(fp_line
			(start 0.499999 0.249999)
			(end -0.499999 0.249999)
			(stroke
				(width 0.1)
				(type default)
			)
			(layer "F.Fab")
		)
		(pad "1" smd rect
			(at -0.4572 0 90)
			(size 0.508 0.5842)
			(layers "F.Cu" "F.Mask" "F.Paste")
			(net "P3V3_10G_B1_VCCT")
		)
		(pad "2" smd rect
			(at 0.4572 0 90)
			(size 0.508 0.5842)
			(layers "F.Cu" "F.Mask" "F.Paste")
			(net "GND")
		)
	)
	(footprint ""
		(layer "F.Cu")
		(at -80.137 10.668)
		(property "Reference" "R40"
			(at -3.048 0.1651 0)
			(unlocked yes)
			(layer "F.SilkS")
			(effects
				(font
					(size 0.762 0.5334)
					(thickness 0.1016)
				)
			)
		)
		(property "Value" ""
			(at 0 0 0)
			(layer "F.Fab")
			(effects
				(font
					(size 1.27 1.27)
				)
			)
		)
		(duplicate_pad_numbers_are_jumpers no)
		(fp_line
			(start 0 -0.381)
			(end 0 0.381)
			(stroke
				(width 0.127)
				(type default)
			)
			(layer "F.SilkS")
		)
		(fp_poly
			(pts
				(xy 1.255601 0.6564) (xy -1.255601 0.6564) (xy -1.255601 -0.656399) (xy 1.255601 -0.656399)
			)
			(stroke
				(width 0)
				(type default)
			)
			(fill no)
			(layer "F.CrtYd")
		)
		(fp_line
			(start -0.800001 -0.399999)
			(end -0.800001 0.399999)
			(stroke
				(width 0.1)
				(type default)
			)
			(layer "F.Fab")
		)
		(fp_line
			(start -0.800001 0.399999)
			(end 0.800001 0.399999)
			(stroke
				(width 0.1)
				(type default)
			)
			(layer "F.Fab")
		)
		(fp_line
			(start 0.800001 -0.399999)
			(end -0.800001 -0.399999)
			(stroke
				(width 0.1)
				(type default)
			)
			(layer "F.Fab")
		)
		(fp_line
			(start 0.800001 0.399999)
			(end 0.800001 -0.399999)
			(stroke
				(width 0.1)
				(type default)
			)
			(layer "F.Fab")
		)
		(pad "1" smd rect
			(at -0.650001 0)
			(size 0.7112 0.8128)
			(layers "F.Cu" "F.Mask" "F.Paste")
			(net "BLADE_B2_MATED_N")
		)
		(pad "2" smd rect
			(at 0.650001 0 180)
			(size 0.7112 0.8128)
			(layers "F.Cu" "F.Mask" "F.Paste")
			(net "GND")
		)
	)
	(footprint ""
		(layer "F.Cu")
		(at -48.2854 9.1186 -90)
		(property "Reference" "C23"
			(at 0.03556 1.28016 90)
			(unlocked yes)
			(layer "F.SilkS")
			(effects
				(font
					(size 0.762 0.5334)
					(thickness 0.1016)
				)
			)
		)
		(property "Value" ""
			(at 0 0 270)
			(layer "F.Fab")
			(effects
				(font
					(size 1.27 1.27)
				)
			)
		)
		(duplicate_pad_numbers_are_jumpers no)
		(fp_line
			(start 0 -0.381)
			(end 0 0.381)
			(stroke
				(width 0.127)
				(type default)
			)
			(layer "F.SilkS")
		)
		(fp_poly
			(pts
				(xy 1.2533 0.6564) (xy -1.253299 0.6564) (xy -1.253299 -0.656399) (xy 1.2533 -0.656399)
			)
			(stroke
				(width 0)
				(type default)
			)
			(fill no)
			(layer "F.CrtYd")
		)
		(fp_line
			(start -0.762 0.381)
			(end 0.762 0.381)
			(stroke
				(width 0.1)
				(type default)
			)
			(layer "F.Fab")
		)
		(fp_line
			(start 0.762 0.381)
			(end 0.762 -0.381)
			(stroke
				(width 0.1)
				(type default)
			)
			(layer "F.Fab")
		)
		(fp_line
			(start -0.762 -0.381)
			(end -0.762 0.381)
			(stroke
				(width 0.1)
				(type default)
			)
			(layer "F.Fab")
		)
		(fp_line
			(start 0.762 -0.381)
			(end -0.762 -0.381)
			(stroke
				(width 0.1)
				(type default)
			)
			(layer "F.Fab")
		)
		(pad "1" smd rect
			(at -0.6477 0 270)
			(size 0.7112 0.8128)
			(layers "F.Cu" "F.Mask" "F.Paste")
			(net "P3V3_40G_B2_VCC_TX")
		)
		(pad "2" smd rect
			(at 0.6477 0 90)
			(size 0.7112 0.8128)
			(layers "F.Cu" "F.Mask" "F.Paste")
			(net "GND")
		)
	)
	(footprint ""
		(layer "F.Cu")
		(at -80.118801 5.016602 180)
		(property "Reference" "R31"
			(at 2.939199 0.025502 0)
			(unlocked yes)
			(layer "F.SilkS")
			(effects
				(font
					(size 0.762 0.5334)
					(thickness 0.1016)
				)
			)
		)
		(property "Value" ""
			(at 0 0 180)
			(layer "F.Fab")
			(effects
				(font
					(size 1.27 1.27)
				)
			)
		)
		(duplicate_pad_numbers_are_jumpers no)
		(fp_line
			(start 0 -0.381)
			(end 0 0.381)
			(stroke
				(width 0.127)
				(type default)
			)
			(layer "F.SilkS")
		)
		(fp_poly
			(pts
				(xy 1.255601 0.6564) (xy -1.255601 0.6564) (xy -1.255601 -0.656399) (xy 1.255601 -0.656399)
			)
			(stroke
				(width 0)
				(type default)
			)
			(fill no)
			(layer "F.CrtYd")
		)
		(fp_line
			(start 0.800001 0.4)
			(end 0.800001 -0.399999)
			(stroke
				(width 0.1)
				(type default)
			)
			(layer "F.Fab")
		)
		(fp_line
			(start 0.800001 -0.399999)
			(end -0.800001 -0.399999)
			(stroke
				(width 0.1)
				(type default)
			)
			(layer "F.Fab")
		)
		(fp_line
			(start -0.800001 0.4)
			(end 0.800001 0.4)
			(stroke
				(width 0.1)
				(type default)
			)
			(layer "F.Fab")
		)
		(fp_line
			(start -0.800001 -0.399999)
			(end -0.800001 0.4)
			(stroke
				(width 0.1)
				(type default)
			)
			(layer "F.Fab")
		)
		(pad "1" smd rect
			(at -0.650001 0 180)
			(size 0.7112 0.8128)
			(layers "F.Cu" "F.Mask" "F.Paste")
			(net "SKU_B2_ID0")
		)
		(pad "2" smd rect
			(at 0.650001 0)
			(size 0.7112 0.8128)
			(layers "F.Cu" "F.Mask" "F.Paste")
			(net "GND")
		)
	)
)
